# S9S_MB_2U (Grand Teton) — schematic netlist excerpt (pin names and nets, part order shuffled) for the footprints in the layout excerpt that follows; sources: Cadence DE-HDL packaged netlist, KiCad conversion of 03242023_DA0F0TMBIJ0_F0T_Motherboard_J_brd_V01_OCP.brd

J7  SCONN288_ADR50017P130CC  SCONN288_ADR50017-P130CC IO  pkg DDR288S_1-1VXB  page 88
  VIN_BULK0  = P12V_S3_AUX_CPU0_NVDIMM
  RFU0  = TP_CHD_CPU0_DIMM1_FRU_0
  VIN_MGMT  = P3V3_AUX
  HSCL  = I3C_SPD_DDRABCD_CPU0_LVC1_SCL_6
  HSDA  = I3C_SPD_DDRABCD_CPU0_LVC1_SDA
  VSS0  = GND
  DQ0_A  = M_D_CPU0_SA_DQ<0>
  VSS1  = GND
  DQ1_A  = M_D_CPU0_SA_DQ<1>
  VSS2  = GND
  DQS0_A_T  = M_D_CPU0_SA_DQS_DP<0>
  DQS0_A_C  = M_D_CPU0_SA_DQS_DN<0>
  VSS3  = GND
  DQ4_A  = M_D_CPU0_SA_DQ<4>
  VSS4  = GND
  DQ5_A  = M_D_CPU0_SA_DQ<5>
  VSS5  = GND
  DQ8_A  = M_D_CPU0_SA_DQ<8>
  VSS6  = GND
  DQ9_A  = M_D_CPU0_SA_DQ<9>
  VSS7  = GND
  DQS1_A_T  = M_D_CPU0_SA_DQS_DP<1>
  DQS1_A_C  = M_D_CPU0_SA_DQS_DN<1>
  VSS8  = GND
  DQ12_A  = M_D_CPU0_SA_DQ<12>
  VSS9  = GND
  DQ13_A  = M_D_CPU0_SA_DQ<13>
  VSS10  = GND
  DQ16_A  = M_D_CPU0_SA_DQ<16>
  VSS11  = GND
  DQ17_A  = M_D_CPU0_SA_DQ<17>
  VSS12  = GND
  DQS2_A_T  = M_D_CPU0_SA_DQS_DP<2>
  DQS2_A_C  = M_D_CPU0_SA_DQS_DN<2>
  VSS13  = GND
  DQ20_A  = M_D_CPU0_SA_DQ<20>
  VSS14  = GND
  DQ21_A  = M_D_CPU0_SA_DQ<21>
  VSS15  = GND
  DQ24_A  = M_D_CPU0_SA_DQ<24>
  VSS16  = GND
  DQ25_A  = M_D_CPU0_SA_DQ<25>
  VSS17  = GND
  DQS3_A_T  = M_D_CPU0_SA_DQS_DP<3>
  DQS3_A_C  = M_D_CPU0_SA_DQS_DN<3>
  VSS18  = GND
  DQ28_A  = M_D_CPU0_SA_DQ<28>
  VSS19  = GND
  DQ29_A  = M_D_CPU0_SA_DQ<29>
  VSS20  = GND
  CB0_A  = M_D_CPU0_SA_CB<0>
  VSS21  = GND
  CB1_A  = M_D_CPU0_SA_CB<1>
  VSS22  = GND
  DQS4_A_T  = M_D_CPU0_SA_DQS_DP<4>
  DQS4_A_C  = M_D_CPU0_SA_DQS_DN<4>
  VSS23  = GND
  CB4_A  = M_D_CPU0_SA_CB<4>
  VSS24  = GND
  CB5_A  = M_D_CPU0_SA_CB<5>
  VSS25  = GND
  ALERT_N  = M_D_CPU0_ALERT_N
  VSS26  = GND
  CS0_A_N  = M_D_CPU0_SA_CS_N<0>
  VSS27  = GND
  CA0_A  = M_D_CPU0_SA_CA<0>
  VSS28  = GND
  CA2_A  = M_D_CPU0_SA_CA<2>
  VSS29  = GND
  CA4_A  = M_D_CPU0_SA_CA<4>
  VSS30  = GND
  CA6_A  = M_D_CPU0_SA_CA<6>
  VSS31  = GND
  PAR_A  = M_D_CPU0_SA_PAR
  VSS32  = GND
  CA0_B  = M_D_CPU0_SB_CA<0>
  VSS33  = GND
  CA2_B  = M_D_CPU0_SB_CA<2>
  VSS34  = GND
  CA4_B  = M_D_CPU0_SB_CA<4>
  VSS35  = GND
  CA6_B  = M_D_CPU0_SB_CA<6>
  VSS36  = GND
  CS0_B_N  = M_D_CPU0_SB_CS_N<0>
  VSS37  = GND
  \lbd||rsp_a_n\  = M_D_CPU0_SA_RSP<0>
  \lbs||rsp_b_n\  = M_D_CPU0_SB_RSP<0>
  VSS38  = GND
  CB4_B  = M_D_CPU0_SB_CB<4>
  VSS39  = GND
  CB5_B  = M_D_CPU0_SB_CB<5>
  VSS40  = GND
  \dqs9_b_t||tdqs9_b_t||dbi4_b_n\  = M_D_CPU0_SB_DQS_DP<9>
  \dqs9_b_c||tdqs9_b_c\  = M_D_CPU0_SB_DQS_DN<9>
  VSS41  = GND
  CB0_B  = M_D_CPU0_SB_CB<0>
  VSS42  = GND
  CB1_B  = M_D_CPU0_SB_CB<1>
  VSS43  = GND
  DQ0_B  = M_D_CPU0_SB_DQ<0>
  VSS44  = GND
  DQ1_B  = M_D_CPU0_SB_DQ<1>
  VSS45  = GND
  DQS0_B_T  = M_D_CPU0_SB_DQS_DP<0>
  DQS0_B_C  = M_D_CPU0_SB_DQS_DN<0>
  VSS46  = GND
  DQ4_B  = M_D_CPU0_SB_DQ<4>
  VSS47  = GND
  DQ5_B  = M_D_CPU0_SB_DQ<5>
  VSS48  = GND
  DQ8_B  = M_D_CPU0_SB_DQ<8>
  VSS49  = GND
  DQ9_B  = M_D_CPU0_SB_DQ<9>
  VSS50  = GND
  DQS1_B_T  = M_D_CPU0_SB_DQS_DP<1>
  DQS1_B_C  = M_D_CPU0_SB_DQS_DN<1>
  VSS51  = GND
  DQ12_B  = M_D_CPU0_SB_DQ<12>
  VSS52  = GND
  DQ13_B  = M_D_CPU0_SB_DQ<13>
  VSS53  = GND
  DQ16_B  = M_D_CPU0_SB_DQ<16>
  VSS54  = GND
  DQ17_B  = M_D_CPU0_SB_DQ<17>
  VSS55  = GND
  DQS2_B_T  = M_D_CPU0_SB_DQS_DP<2>
  DQS2_B_C  = M_D_CPU0_SB_DQS_DN<2>
  VSS56  = GND
  DQ20_B  = M_D_CPU0_SB_DQ<20>
  VSS57  = GND
  DQ21_B  = M_D_CPU0_SB_DQ<21>
  VSS58  = GND
  DQ24_B  = M_D_CPU0_SB_DQ<24>
  VSS59  = GND
  DQ25_B  = M_D_CPU0_SB_DQ<25>
  VSS60  = GND
  DQS3_B_T  = M_D_CPU0_SB_DQS_DP<3>
  DQS3_B_C  = M_D_CPU0_SB_DQS_DN<3>
  VSS61  = GND
  DQ28_B  = M_D_CPU0_SB_DQ<28>
  VSS62  = GND
  DQ29_B  = M_D_CPU0_SB_DQ<29>
  VSS63  = GND
  RFU1  = TP_CHD_CPU0_DIMM1_FRU_1
  VIN_BULK1  = P12V_S3_AUX_CPU0_NVDIMM
  VIN_BULK2  = P12V_S3_AUX_CPU0_NVDIMM
  \pwr_good||fail_n\  = PWRGD_CHD_CPU0_DIMM1
  HSA  = PD_CHD_CPU0_DIMM1_SAA
  RFU2  = TP_CHD_CPU0_DIMM1_FRU_2
  RFU3  = TP_CHD_CPU0_DIMM1_FRU_3
  VSS64  = GND
  DQ2_A  = M_D_CPU0_SA_DQ<2>
  VSS65  = GND
  DQ3_A  = M_D_CPU0_SA_DQ<3>
  VSS66  = GND
  \dqs5_a_c||tdqs5_a_c||dqs5_a_t||tdqs5_a_t\  = M_D_CPU0_SA_DQS_DN<5>
  \dqs5_a_t||tdqs5_a_t\  = M_D_CPU0_SA_DQS_DP<5>
  VSS67  = GND
  DQ6_A  = M_D_CPU0_SA_DQ<6>
  VSS68  = GND
  DQ7_A  = M_D_CPU0_SA_DQ<7>
  VSS69  = GND
  DQ10_A  = M_D_CPU0_SA_DQ<10>
  VSS70  = GND
  DQ11_A  = M_D_CPU0_SA_DQ<11>
  VSS71  = GND
  \dqs6_a_c||tdqs6_a_c||dqs6_a_t||tdqs6_a_t\  = M_D_CPU0_SA_DQS_DN<6>
  \dqs6_a_t||tdqs6_a_t\  = M_D_CPU0_SA_DQS_DP<6>
  VSS72  = GND
  DQ14_A  = M_D_CPU0_SA_DQ<14>
  VSS73  = GND
  DQ15_A  = M_D_CPU0_SA_DQ<15>
  VSS74  = GND
  DQ18_A  = M_D_CPU0_SA_DQ<18>
  VSS75  = GND
  DQ19_A  = M_D_CPU0_SA_DQ<19>
  VSS76  = GND
  \dqs7_a_c||tdqs7_a_c\  = M_D_CPU0_SA_DQS_DN<7>
  \dqs7_a_t||tdqs7_a_t\  = M_D_CPU0_SA_DQS_DP<7>
  VSS77  = GND
  DQ22_A  = M_D_CPU0_SA_DQ<22>
  VSS78  = GND
  DQ23_A  = M_D_CPU0_SA_DQ<23>
  VSS79  = GND
  DQ26_A  = M_D_CPU0_SA_DQ<26>
  VSS80  = GND
  DQ27_A  = M_D_CPU0_SA_DQ<27>
  VSS81  = GND
  \dqs8_a_c||tdqs8_a_c\  = M_D_CPU0_SA_DQS_DN<8>
  \dqs8_a_t||tdqs8_a_t\  = M_D_CPU0_SA_DQS_DP<8>
  VSS82  = GND
  DQ30_A  = M_D_CPU0_SA_DQ<30>
  VSS83  = GND
  DQ31_A  = M_D_CPU0_SA_DQ<31>
  VSS84  = GND
  CB2_A  = M_D_CPU0_SA_CB<2>
  VSS85  = GND
  CB3_A  = M_D_CPU0_SA_CB<3>
  VSS86  = GND
  \dqs9_a_c||tdqs9_a_c\  = M_D_CPU0_SA_DQS_DN<9>
  \dqs9_a_t||tdqs9_a_t\  = M_D_CPU0_SA_DQS_DP<9>
  VSS87  = GND
  CB6_A  = M_D_CPU0_SA_CB<6>
  VSS88  = GND
  CB7_A  = M_D_CPU0_SA_CB<7>
  VSS89  = GND
  RESET_N  = RST_M_CD_CPU0_FPGA_N
  VSS90  = GND
  CS1_A_N  = M_D_CPU0_SA_CS_N<1>
  VSS91  = GND
  CA1_A  = M_D_CPU0_SA_CA<1>
  VSS92  = GND
  CA3_A  = M_D_CPU0_SA_CA<3>
  VSS93  = GND
  CA5_A  = M_D_CPU0_SA_CA<5>
  VSS94  = GND
  CK_T  = M_D_CPU0_CLK_DP<0>
  CK_C  = M_D_CPU0_CLK_DN<0>
  VSS95  = GND
  RFU4  = TP_CHD_CPU0_DIMM1_FRU_4
  CA1_B  = M_D_CPU0_SB_CA<1>
  VSS96  = GND
  CA3_B  = M_D_CPU0_SB_CA<3>
  VSS97  = GND
  CA5_B  = M_D_CPU0_SB_CA<5>
  VSS98  = GND
  PAR_B  = M_D_CPU0_SB_PAR
  VSS99  = GND
  CS1_B_N  = M_D_CPU0_SB_CS_N<1>
  VSS100  = GND
  RFU5  = TP_CHD_CPU0_DIMM1_FRU_5
  RFU6  = TP_CHD_CPU0_DIMM1_FRU_6
  VSS101  = GND
  CB6_B  = M_D_CPU0_SB_CB<6>
  VSS102  = GND
  CB7_B  = M_D_CPU0_SB_CB<7>
  VSS103  = GND
  DQS4_B_C  = M_D_CPU0_SB_DQS_DN<4>
  DQS4_B_T  = M_D_CPU0_SB_DQS_DP<4>
  VSS104  = GND
  CB2_B  = M_D_CPU0_SB_CB<2>
  VSS105  = GND
  CB3_B  = M_D_CPU0_SB_CB<3>
  VSS106  = GND
  DQ2_B  = M_D_CPU0_SB_DQ<2>
  VSS107  = GND
  DQ3_B  = M_D_CPU0_SB_DQ<3>
  VSS108  = GND
  \dqs5_b_c||tdqs5_b_c\  = M_D_CPU0_SB_DQS_DN<5>
  \dqs5_b_t||tdqs5_b_t\  = M_D_CPU0_SB_DQS_DP<5>
  VSS109  = GND
  DQ6_B  = M_D_CPU0_SB_DQ<6>
  VSS110  = GND
  DQ7_B  = M_D_CPU0_SB_DQ<7>
  VSS111  = GND
  DQ10_B  = M_D_CPU0_SB_DQ<10>
  VSS112  = GND
  DQ11_B  = M_D_CPU0_SB_DQ<11>
  VSS113  = GND
  \dqs6_b_c||tdqs6_b_c\  = M_D_CPU0_SB_DQS_DN<6>
  \dqs6_b_t||tdqs6_b_t\  = M_D_CPU0_SB_DQS_DP<6>
  VSS114  = GND
  DQ14_B  = M_D_CPU0_SB_DQ<14>
  VSS115  = GND
  DQ15_B  = M_D_CPU0_SB_DQ<15>
  VSS116  = GND
  DQ18_B  = M_D_CPU0_SB_DQ<18>
  VSS117  = GND
  DQ19_B  = M_D_CPU0_SB_DQ<19>
  VSS118  = GND
  \dqs7_b_c||tdqs7_b_c\  = M_D_CPU0_SB_DQS_DN<7>
  \dqs7_b_t||tdqs7_b_t\  = M_D_CPU0_SB_DQS_DP<7>
  VSS119  = GND
  DQ22_B  = M_D_CPU0_SB_DQ<22>
  VSS120  = GND
  DQ23_B  = M_D_CPU0_SB_DQ<23>
  VSS121  = GND
  DQ26_B  = M_D_CPU0_SB_DQ<26>
  VSS122  = GND
  DQ27_B  = M_D_CPU0_SB_DQ<27>
  VSS123  = GND
  \dqs8_b_c||tdqs8_b_c\  = M_D_CPU0_SB_DQS_DN<8>
  \dqs8_b_t||tdqs8_b_t\  = M_D_CPU0_SB_DQS_DP<8>
  VSS124  = GND
  DQ30_B  = M_D_CPU0_SB_DQ<30>
  VSS125  = GND
  DQ31_B  = M_D_CPU0_SB_DQ<31>
  VSS126  = GND
  G1  = GND
  G2  = GND
  G3  = GND

(kicad_pcb
	(version 20260206)
	(generator "pcbnew")
	(generator_version "10.0")
	(general
		(thickness 1.6)
		(legacy_teardrops no)
	)
	(paper "A4")
	(title_block
		(title "03242023_DA0F0TMBIJ0_F0T_Motherboard_J_brd_V01_OCP.brd")
		(comment 1 "Grand Teton / footprint 37 of 6105 (J7), pads 138-182 of 291")
	)
	(layers
		(0 "F.Cu" signal "TOP")
		(4 "In1.Cu" signal "GND")
		(6 "In2.Cu" signal "IN1")
		(8 "In3.Cu" signal "GND1")
		(10 "In4.Cu" signal "IN2")
		(12 "In5.Cu" signal "GND2")
		(14 "In6.Cu" signal "IN3")
		(16 "In7.Cu" signal "GND3")
		(18 "In8.Cu" signal "VCC")
		(20 "In9.Cu" signal "VCC1")
		(22 "In10.Cu" signal "GND4")
		(24 "In11.Cu" signal "IN4")
		(26 "In12.Cu" signal "GND5")
		(28 "In13.Cu" signal "IN5")
		(30 "In14.Cu" signal "GND6")
		(32 "In15.Cu" signal "IN6")
		(34 "In16.Cu" signal "GND7")
		(2 "B.Cu" signal "BOTTOM")
		(9 "F.Adhes" user "F.Adhesive")
		(11 "B.Adhes" user "B.Adhesive")
		(13 "F.Paste" user "Package Geometry/Pastemask Top")
		(15 "B.Paste" user "Package Geometry/Pastemask Bottom")
		(5 "F.SilkS" user "Ref Des/Silkscreen Top")
		(7 "B.SilkS" user "Ref Des/Silkscreen Bottom")
		(1 "F.Mask" user "Board Geometry/Soldermask Top")
		(3 "B.Mask" user "Board Geometry/Soldermask Bottom")
		(17 "Dwgs.User" user "User.Drawings")
		(19 "Cmts.User" user "User.Comments")
		(21 "Eco1.User" user "User.Eco1")
		(23 "Eco2.User" user "User.Eco2")
		(25 "Edge.Cuts" user "Board Geometry/Outline")
		(27 "Margin" user)
		(31 "F.CrtYd" user "Package Geometry/Place Bound Top")
		(29 "B.CrtYd" user "Package Geometry/Place Bound Bottom")
		(35 "F.Fab" user "Ref Des/Assembly Top")
		(33 "B.Fab" user "Ref Des/Assembly Bottom")
	)
	(footprint ""
		(layer "F.Cu")
		(at 258.130548 -258.091686)
		(property "Reference" "J7"
			(at -3.683 -81.702148 0)
			(unlocked yes)
			(layer "F.SilkS")
			(effects
				(font
					(size 0.7874 0.5842)
					(thickness 0.1524)
				)
				(justify left)
			)
		)
		(property "Value" ""
			(at 0 0 0)
			(layer "F.Fab")
			(effects
				(font
					(size 1.27 1.27)
				)
			)
		)
		(duplicate_pad_numbers_are_jumpers no)
		(pad "138" smd rect
			(at -2.050034 58.224928 270)
			(size 0.519938 1.4986)
			(layers "F.Cu" "F.Mask" "F.Paste")
			(net "M_D_CPU0_SB_DQS_DN<3>")
		)
		(pad "139" smd rect
			(at -2.050034 59.075066 270)
			(size 0.519938 1.4986)
			(layers "F.Cu" "F.Mask" "F.Paste")
			(net "GND")
		)
		(pad "140" smd rect
			(at -2.050034 59.92495 270)
			(size 0.519938 1.4986)
			(layers "F.Cu" "F.Mask" "F.Paste")
			(net "M_D_CPU0_SB_DQ<28>")
		)
		(pad "141" smd rect
			(at -2.050034 60.775088 270)
			(size 0.519938 1.4986)
			(layers "F.Cu" "F.Mask" "F.Paste")
			(net "GND")
		)
		(pad "142" smd rect
			(at -2.050034 61.624972 270)
			(size 0.519938 1.4986)
			(layers "F.Cu" "F.Mask" "F.Paste")
			(net "M_D_CPU0_SB_DQ<29>")
		)
		(pad "143" smd rect
			(at -2.050034 62.47511 270)
			(size 0.519938 1.4986)
			(layers "F.Cu" "F.Mask" "F.Paste")
			(net "GND")
		)
		(pad "144" smd rect
			(at -2.050034 63.324994 270)
			(size 0.519938 1.4986)
			(layers "F.Cu" "F.Mask" "F.Paste")
			(net "TP_CHD_CPU0_DIMM1_FRU_1")
		)
		(pad "145" smd rect
			(at 2.050034 -63.324994 270)
			(size 0.519938 1.4986)
			(layers "F.Cu" "F.Mask" "F.Paste")
			(net "P12V_S3_AUX_CPU0_NVDIMM")
		)
		(pad "146" smd rect
			(at 2.050034 -62.47511 270)
			(size 0.519938 1.4986)
			(layers "F.Cu" "F.Mask" "F.Paste")
			(net "P12V_S3_AUX_CPU0_NVDIMM")
		)
		(pad "147" smd rect
			(at 2.050034 -61.624972 270)
			(size 0.519938 1.4986)
			(layers "F.Cu" "F.Mask" "F.Paste")
			(net "PWRGD_CHD_CPU0_DIMM1")
		)
		(pad "148" smd rect
			(at 2.050034 -60.775088 270)
			(size 0.519938 1.4986)
			(layers "F.Cu" "F.Mask" "F.Paste")
			(net "PD_CHD_CPU0_DIMM1_SAA")
		)
		(pad "149" smd rect
			(at 2.050034 -59.92495 270)
			(size 0.519938 1.4986)
			(layers "F.Cu" "F.Mask" "F.Paste")
			(net "TP_CHD_CPU0_DIMM1_FRU_2")
		)
		(pad "150" smd rect
			(at 2.050034 -59.075066 270)
			(size 0.519938 1.4986)
			(layers "F.Cu" "F.Mask" "F.Paste")
			(net "TP_CHD_CPU0_DIMM1_FRU_3")
		)
		(pad "151" smd rect
			(at 2.050034 -58.224928 270)
			(size 0.519938 1.4986)
			(layers "F.Cu" "F.Mask" "F.Paste")
			(net "GND")
		)
		(pad "152" smd rect
			(at 2.050034 -57.375044 270)
			(size 0.519938 1.4986)
			(layers "F.Cu" "F.Mask" "F.Paste")
			(net "M_D_CPU0_SA_DQ<2>")
		)
		(pad "153" smd rect
			(at 2.050034 -56.524906 270)
			(size 0.519938 1.4986)
			(layers "F.Cu" "F.Mask" "F.Paste")
			(net "GND")
		)
		(pad "154" smd rect
			(at 2.050034 -55.675022 270)
			(size 0.519938 1.4986)
			(layers "F.Cu" "F.Mask" "F.Paste")
			(net "M_D_CPU0_SA_DQ<3>")
		)
		(pad "155" smd rect
			(at 2.050034 -54.824884 270)
			(size 0.519938 1.4986)
			(layers "F.Cu" "F.Mask" "F.Paste")
			(net "GND")
		)
		(pad "156" smd rect
			(at 2.050034 -53.975 270)
			(size 0.519938 1.4986)
			(layers "F.Cu" "F.Mask" "F.Paste")
			(net "M_D_CPU0_SA_DQS_DN<5>")
		)
		(pad "157" smd rect
			(at 2.050034 -53.125116 270)
			(size 0.519938 1.4986)
			(layers "F.Cu" "F.Mask" "F.Paste")
			(net "M_D_CPU0_SA_DQS_DP<5>")
		)
		(pad "158" smd rect
			(at 2.050034 -52.274978 270)
			(size 0.519938 1.4986)
			(layers "F.Cu" "F.Mask" "F.Paste")
			(net "GND")
		)
		(pad "159" smd rect
			(at 2.050034 -51.425094 270)
			(size 0.519938 1.4986)
			(layers "F.Cu" "F.Mask" "F.Paste")
			(net "M_D_CPU0_SA_DQ<6>")
		)
		(pad "160" smd rect
			(at 2.050034 -50.574956 270)
			(size 0.519938 1.4986)
			(layers "F.Cu" "F.Mask" "F.Paste")
			(net "GND")
		)
		(pad "161" smd rect
			(at 2.050034 -49.725072 270)
			(size 0.519938 1.4986)
			(layers "F.Cu" "F.Mask" "F.Paste")
			(net "M_D_CPU0_SA_DQ<7>")
		)
		(pad "162" smd rect
			(at 2.050034 -48.874934 270)
			(size 0.519938 1.4986)
			(layers "F.Cu" "F.Mask" "F.Paste")
			(net "GND")
		)
		(pad "163" smd rect
			(at 2.050034 -48.02505 270)
			(size 0.519938 1.4986)
			(layers "F.Cu" "F.Mask" "F.Paste")
			(net "M_D_CPU0_SA_DQ<10>")
		)
		(pad "164" smd rect
			(at 2.050034 -47.174912 270)
			(size 0.519938 1.4986)
			(layers "F.Cu" "F.Mask" "F.Paste")
			(net "GND")
		)
		(pad "165" smd rect
			(at 2.050034 -46.325028 270)
			(size 0.519938 1.4986)
			(layers "F.Cu" "F.Mask" "F.Paste")
			(net "M_D_CPU0_SA_DQ<11>")
		)
		(pad "166" smd rect
			(at 2.050034 -45.47489 270)
			(size 0.519938 1.4986)
			(layers "F.Cu" "F.Mask" "F.Paste")
			(net "GND")
		)
		(pad "167" smd rect
			(at 2.050034 -44.625006 270)
			(size 0.519938 1.4986)
			(layers "F.Cu" "F.Mask" "F.Paste")
			(net "M_D_CPU0_SA_DQS_DN<6>")
		)
		(pad "168" smd rect
			(at 2.050034 -43.775122 270)
			(size 0.519938 1.4986)
			(layers "F.Cu" "F.Mask" "F.Paste")
			(net "M_D_CPU0_SA_DQS_DP<6>")
		)
		(pad "169" smd rect
			(at 2.050034 -42.924984 270)
			(size 0.519938 1.4986)
			(layers "F.Cu" "F.Mask" "F.Paste")
			(net "GND")
		)
		(pad "170" smd rect
			(at 2.050034 -42.0751 270)
			(size 0.519938 1.4986)
			(layers "F.Cu" "F.Mask" "F.Paste")
			(net "M_D_CPU0_SA_DQ<14>")
		)
		(pad "171" smd rect
			(at 2.050034 -41.224962 270)
			(size 0.519938 1.4986)
			(layers "F.Cu" "F.Mask" "F.Paste")
			(net "GND")
		)
		(pad "172" smd rect
			(at 2.050034 -40.375078 270)
			(size 0.519938 1.4986)
			(layers "F.Cu" "F.Mask" "F.Paste")
			(net "M_D_CPU0_SA_DQ<15>")
		)
		(pad "173" smd rect
			(at 2.050034 -39.52494 270)
			(size 0.519938 1.4986)
			(layers "F.Cu" "F.Mask" "F.Paste")
			(net "GND")
		)
		(pad "174" smd rect
			(at 2.050034 -38.675056 270)
			(size 0.519938 1.4986)
			(layers "F.Cu" "F.Mask" "F.Paste")
			(net "M_D_CPU0_SA_DQ<18>")
		)
		(pad "175" smd rect
			(at 2.050034 -37.824918 270)
			(size 0.519938 1.4986)
			(layers "F.Cu" "F.Mask" "F.Paste")
			(net "GND")
		)
		(pad "176" smd rect
			(at 2.050034 -36.975034 270)
			(size 0.519938 1.4986)
			(layers "F.Cu" "F.Mask" "F.Paste")
			(net "M_D_CPU0_SA_DQ<19>")
		)
		(pad "177" smd rect
			(at 2.050034 -36.124896 270)
			(size 0.519938 1.4986)
			(layers "F.Cu" "F.Mask" "F.Paste")
			(net "GND")
		)
		(pad "178" smd rect
			(at 2.050034 -35.275012 270)
			(size 0.519938 1.4986)
			(layers "F.Cu" "F.Mask" "F.Paste")
			(net "M_D_CPU0_SA_DQS_DN<7>")
		)
		(pad "179" smd rect
			(at 2.050034 -34.425128 270)
			(size 0.519938 1.4986)
			(layers "F.Cu" "F.Mask" "F.Paste")
			(net "M_D_CPU0_SA_DQS_DP<7>")
		)
		(pad "180" smd rect
			(at 2.050034 -33.57499 270)
			(size 0.519938 1.4986)
			(layers "F.Cu" "F.Mask" "F.Paste")
			(net "GND")
		)
		(pad "181" smd rect
			(at 2.050034 -32.725106 270)
			(size 0.519938 1.4986)
			(layers "F.Cu" "F.Mask" "F.Paste")
			(net "M_D_CPU0_SA_DQ<22>")
		)
		(pad "182" smd rect
			(at 2.050034 -31.874968 270)
			(size 0.519938 1.4986)
			(layers "F.Cu" "F.Mask" "F.Paste")
			(net "GND")
		)
	)
)
